# TIMECARD (Time Appliance Project (Time Card)) — schematic netlist excerpt (pin names and nets, part order shuffled) for the footprints in the layout excerpt that follows; sources: Cadence DE-HDL packaged netlist, KiCad conversion of R4006-B0001-02_R01.brd

ME1  NUT  pkg P_NUT_166CT244CB198_V1_H380  page 34 : \1\ = SG
DS3  OPTICAL  pkg SMC_DS_063X031_V4  page 26 : A = UNNAMED_14_OPTICAL_I136_A ; C = LED_DATOUT1

(kicad_pcb
	(version 20260206)
	(generator "pcbnew")
	(generator_version "10.0")
	(general
		(thickness 1.6)
		(legacy_teardrops no)
	)
	(paper "A4")
	(title_block
		(title "timecard-production-celestica-r4006 — R4006-B0001-02_R01.brd")
		(comment 1 "Time Appliance Project (Time Card) / footprints 632-633 of 1113")
	)
	(layers
		(0 "F.Cu" signal "TOP")
		(4 "In1.Cu" signal "L02_GND1")
		(6 "In2.Cu" signal "L03_SIG1")
		(8 "In3.Cu" signal "L04_GND2")
		(10 "In4.Cu" signal "L05_VCC1")
		(12 "In5.Cu" signal "L06_VCC2")
		(14 "In6.Cu" signal "L07_GND3")
		(16 "In7.Cu" signal "L08_SIG2")
		(18 "In8.Cu" signal "L09_GND4")
		(2 "B.Cu" signal "BOTTOM")
		(9 "F.Adhes" user "F.Adhesive")
		(11 "B.Adhes" user "B.Adhesive")
		(13 "F.Paste" user "Package Geometry/Pastemask Top")
		(15 "B.Paste" user "Package Geometry/Pastemask Bottom")
		(5 "F.SilkS" user "Ref Des/Silkscreen Top")
		(7 "B.SilkS" user "Ref Des/Silkscreen Bottom")
		(1 "F.Mask" user "Board Geometry/Soldermask Top")
		(3 "B.Mask" user "Board Geometry/Soldermask Bottom")
		(17 "Dwgs.User" user "User.Drawings")
		(19 "Cmts.User" user "User.Comments")
		(21 "Eco1.User" user "User.Eco1")
		(23 "Eco2.User" user "User.Eco2")
		(25 "Edge.Cuts" user "Board Geometry/Outline")
		(27 "Margin" user)
		(31 "F.CrtYd" user "Package Geometry/Place Bound Top")
		(29 "B.CrtYd" user "Package Geometry/Place Bound Bottom")
		(35 "F.Fab" user "Ref Des/Assembly Top")
		(33 "B.Fab" user "Ref Des/Assembly Bottom")
	)
	(footprint ""
		(layer "F.Cu")
		(at 144.050004 -107.849924 -90)
		(property "Reference" "DS3"
			(at 0.534924 1.448054 90)
			(unlocked yes)
			(layer "F.SilkS")
			(effects
				(font
					(size 0.635 0.4064)
					(thickness 0.1524)
				)
			)
		)
		(property "Value" ""
			(at 0 0 270)
			(layer "F.Fab")
			(effects
				(font
					(size 1.27 1.27)
				)
			)
		)
		(property "User Part Number" "PARTNUM*"
			(at 0.1778 2.422881 270)
			(unlocked yes)
			(layer "Cmts.User")
			(hide yes)
			(effects
				(font
					(size 0.786892 0.583946)
					(thickness 0.000001)
				)
			)
		)
		(property "Device Type" "OPTICAL-G170-10143-01"
			(at 0.1778 1.483081 270)
			(unlocked yes)
			(layer "F.Fab")
			(hide yes)
			(effects
				(font
					(size 0.786892 0.583946)
					(thickness 0.000001)
				)
			)
		)
		(duplicate_pad_numbers_are_jumpers no)
		(fp_line
			(start -1.3208 1.2192)
			(end -2.5908 1.2192)
			(stroke
				(width 0.1)
				(type default)
			)
			(layer "F.SilkS")
		)
		(fp_line
			(start -1.397508 0.704088)
			(end -1.397508 -0.704088)
			(stroke
				(width 0.1)
				(type default)
			)
			(layer "F.SilkS")
		)
		(fp_line
			(start 1.397508 0.704088)
			(end -1.397508 0.704088)
			(stroke
				(width 0.1)
				(type default)
			)
			(layer "F.SilkS")
		)
		(fp_line
			(start -1.9558 0.5842)
			(end -1.9558 1.8542)
			(stroke
				(width 0.1)
				(type default)
			)
			(layer "F.SilkS")
		)
		(fp_line
			(start -1.397508 -0.704088)
			(end 1.397508 -0.704088)
			(stroke
				(width 0.1)
				(type default)
			)
			(layer "F.SilkS")
		)
		(fp_line
			(start 1.397508 -0.704088)
			(end 1.397508 0.704088)
			(stroke
				(width 0.1)
				(type default)
			)
			(layer "F.SilkS")
		)
		(fp_rect
			(start 1.905508 0.704088)
			(end 1.397508 -0.704088)
			(stroke
				(width 0)
				(type default)
			)
			(fill yes)
			(layer "F.SilkS")
		)
		(fp_rect
			(start 1.905508 0.958088)
			(end -1.651508 -0.958088)
			(stroke
				(width 0)
				(type default)
			)
			(fill no)
			(layer "F.CrtYd")
		)
		(fp_line
			(start -1.3208 0.9652)
			(end -2.5908 0.9652)
			(stroke
				(width 0.1)
				(type default)
			)
			(layer "F.Fab")
		)
		(fp_line
			(start -0.850138 0.450088)
			(end 0.850138 0.450088)
			(stroke
				(width 0.1)
				(type default)
			)
			(layer "F.Fab")
		)
		(fp_line
			(start 0.850138 0.450088)
			(end 0.850138 -0.450088)
			(stroke
				(width 0.1)
				(type default)
			)
			(layer "F.Fab")
		)
		(fp_line
			(start -1.9558 0.3302)
			(end -1.9558 1.6002)
			(stroke
				(width 0.1)
				(type default)
			)
			(layer "F.Fab")
		)
		(fp_line
			(start -0.850138 -0.450088)
			(end -0.850138 0.450088)
			(stroke
				(width 0.1)
				(type default)
			)
			(layer "F.Fab")
		)
		(fp_line
			(start 0.850138 -0.450088)
			(end -0.850138 -0.450088)
			(stroke
				(width 0.1)
				(type default)
			)
			(layer "F.Fab")
		)
		(fp_rect
			(start 0.850138 0.450088)
			(end 0.342138 -0.450088)
			(stroke
				(width 0)
				(type default)
			)
			(fill yes)
			(layer "F.Fab")
		)
		(fp_text user "A"
			(at -1.973326 -0.729996 0)
			(unlocked yes)
			(layer "F.SilkS")
			(effects
				(font
					(size 0.635 0.4064)
					(thickness 0.1524)
				)
			)
		)
		(fp_text user "C"
			(at 1.201674 -1.237996 0)
			(unlocked yes)
			(layer "F.SilkS")
			(effects
				(font
					(size 0.635 0.4064)
					(thickness 0.1524)
				)
			)
		)
		(fp_text user "A"
			(at -1.838706 -0.094996 0)
			(unlocked yes)
			(layer "F.Fab")
			(effects
				(font
					(size 0.7874 0.5842)
					(thickness 0.1524)
				)
			)
		)
		(fp_text user "C"
			(at 0.955294 -0.983996 0)
			(unlocked yes)
			(layer "F.Fab")
			(effects
				(font
					(size 0.7874 0.5842)
					(thickness 0.1524)
				)
			)
		)
		(pad "A" smd rect
			(at -0.749808 0 270)
			(size 0.7874 0.7874)
			(layers "F.Cu" "F.Mask" "F.Paste")
			(net "UNNAMED_14_OPTICAL_I136_A")
		)
		(pad "C" smd rect
			(at 0.749808 0 270)
			(size 0.7874 0.7874)
			(layers "F.Cu" "F.Mask" "F.Paste")
			(net "LED_DATOUT1")
		)
	)
	(footprint ""
		(layer "F.Cu")
		(at 65.000124 -104.650032)
		(property "Reference" "ME1"
			(at -0.801624 4.359402 0)
			(unlocked yes)
			(layer "F.SilkS")
			(effects
				(font
					(size 0.7874 0.5842)
					(thickness 0.1524)
				)
				(justify left)
			)
		)
		(property "Value" ""
			(at 0 0 0)
			(layer "F.Fab")
			(effects
				(font
					(size 1.27 1.27)
				)
			)
		)
		(property "User Part Number" "PARTNUM*"
			(at -3.048 5.242306 0)
			(unlocked yes)
			(layer "Cmts.User")
			(hide yes)
			(effects
				(font
					(size 0.7874 0.5842)
					(thickness 0.1524)
				)
				(justify left)
			)
		)
		(property "Device Type" "NUT-G340-10437-01"
			(at -1.4732 4.226306 0)
			(unlocked yes)
			(layer "F.Fab")
			(hide yes)
			(effects
				(font
					(size 0.7874 0.5842)
					(thickness 0.1524)
				)
				(justify left)
			)
		)
		(duplicate_pad_numbers_are_jumpers no)
		(fp_circle
			(center 0 0)
			(end 3.3528 0)
			(stroke
				(width 0.1)
				(type default)
			)
			(fill no)
			(layer "F.SilkS")
		)
		(fp_poly
			(pts
				(arc
					(start -2.102612 -0.1524)
					(mid -1.490671 -1.490671)
					(end -0.1524 -2.102612)
				)
				(arc
					(start -0.1524 -3.171444)
					(mid -2.245137 -2.245137)
					(end -3.171444 -0.1524)
				)
			)
			(stroke
				(width 0)
				(type default)
			)
			(fill yes)
			(layer "F.Paste")
		)
		(fp_poly
			(pts
				(arc
					(start -0.1524 2.102612)
					(mid -1.490671 1.490671)
					(end -2.102612 0.1524)
				)
				(arc
					(start -3.171444 0.1524)
					(mid -2.245137 2.245137)
					(end -0.1524 3.171444)
				)
			)
			(stroke
				(width 0)
				(type default)
			)
			(fill yes)
			(layer "F.Paste")
		)
		(fp_poly
			(pts
				(arc
					(start 0.1524 -2.102612)
					(mid 1.490671 -1.490671)
					(end 2.102612 -0.1524)
				)
				(arc
					(start 3.171444 -0.1524)
					(mid 2.245137 -2.245137)
					(end 0.1524 -3.171444)
				)
			)
			(stroke
				(width 0)
				(type default)
			)
			(fill yes)
			(layer "F.Paste")
		)
		(fp_poly
			(pts
				(arc
					(start 2.102612 0.1524)
					(mid 1.490671 1.490671)
					(end 0.1524 2.102612)
				)
				(arc
					(start 0.1524 3.171444)
					(mid 2.245137 2.245137)
					(end 3.171444 0.1524)
				)
			)
			(stroke
				(width 0)
				(type default)
			)
			(fill yes)
			(layer "F.Paste")
		)
		(fp_rect
			(start -7.5946 7.5946)
			(end 7.5946 -7.5946)
			(stroke
				(width 0)
				(type default)
			)
			(fill no)
			(layer "B.CrtYd")
		)
		(fp_poly
			(pts
				(arc
					(start 3.6068 0)
					(mid -3.6068 0)
					(end 3.6068 0)
				)
			)
			(stroke
				(width 0)
				(type default)
			)
			(fill no)
			(layer "F.CrtYd")
		)
		(fp_circle
			(center 0 0)
			(end 2.8448 0)
			(stroke
				(width 0.1)
				(type default)
			)
			(fill no)
			(layer "F.Fab")
		)
		(pad "1" thru_hole circle
			(at 0 0)
			(size 6.1976 6.1976)
			(drill 4.2164)
			(layers "*.Cu" "*.Mask")
			(remove_unused_layers no)
			(net "SG")
			(padstack
				(mode front_inner_back)
				(layer "Inner"
					(shape circle)
					(size 5.0292 5.0292)
					(clearance -0.1143)
				)
				(layer "B.Cu"
					(shape circle)
					(size 5.0292 5.0292)
				)
			)
		)
	)
)
